(kicad_pcb
	(version 20260206)
	(generator "pcbnew")
	(generator_version "10.0")
	(general
		(thickness 1.6)
		(legacy_teardrops no)
	)
	(paper "A4")
	(title_block
		(title "Bryce Canyon_IOM_IOC_16318-2_OCP.brd")
		(comment 1 "Bryce Canyon / footprints 1468-1476 of 1605")
	)
	(layers
		(0 "F.Cu" signal "TOP")
		(4 "In1.Cu" signal "L2GND")
		(6 "In2.Cu" signal "L3")
		(8 "In3.Cu" signal "L4VCC")
		(10 "In4.Cu" signal "L5VCC")
		(12 "In5.Cu" signal "L6")
		(14 "In6.Cu" signal "L7GND")
		(2 "B.Cu" signal "BOTTOM")
		(9 "F.Adhes" user "F.Adhesive")
		(11 "B.Adhes" user "B.Adhesive")
		(13 "F.Paste" user "Package Geometry/Pastemask Top")
		(15 "B.Paste" user "Package Geometry/Pastemask Bottom")
		(5 "F.SilkS" user "Ref Des/Silkscreen Top")
		(7 "B.SilkS" user "Ref Des/Silkscreen Bottom")
		(1 "F.Mask" user "Board Geometry/Soldermask Top")
		(3 "B.Mask" user "Board Geometry/Soldermask Bottom")
		(17 "Dwgs.User" user "User.Drawings")
		(19 "Cmts.User" user "User.Comments")
		(21 "Eco1.User" user "User.Eco1")
		(23 "Eco2.User" user "User.Eco2")
		(25 "Edge.Cuts" user "Board Geometry/Outline")
		(27 "Margin" user)
		(31 "F.CrtYd" user "Package Geometry/Place Bound Top")
		(29 "B.CrtYd" user "Package Geometry/Place Bound Bottom")
		(35 "F.Fab" user "Ref Des/Assembly Top")
		(33 "B.Fab" user "Ref Des/Assembly Bottom")
	)
	(footprint ""
		(layer "B.Cu")
		(at 199.92848 -71.88962 90)
		(property "Reference" "C382"
			(at 0 0 90)
			(layer "B.SilkS")
			(hide yes)
			(effects
				(font
					(size 1.27 1.27)
				)
				(justify mirror)
			)
		)
		(property "Value" "SCD1U6D3V1KX-GP"
			(at 2.8321 -1.7399 90)
			(unlocked yes)
			(layer "B.Fab")
			(hide yes)
			(effects
				(font
					(size 1.016 1.016)
					(thickness 0.1524)
				)
				(justify mirror)
			)
		)
		(property "Device Type" "C0201H13"
			(at 2.8321 -3.2639 90)
			(unlocked yes)
			(layer "B.Fab")
			(hide yes)
			(effects
				(font
					(size 1.016 1.016)
					(thickness 0.1524)
				)
				(justify mirror)
			)
		)
		(duplicate_pad_numbers_are_jumpers no)
		(fp_rect
			(start 0.2794 0.6477)
			(end -0.2794 -0.6477)
			(stroke
				(width 0)
				(type default)
			)
			(fill no)
			(layer "B.CrtYd")
		)
		(fp_rect
			(start 0.2794 0.6477)
			(end -0.2794 -0.6477)
			(stroke
				(width 0)
				(type default)
			)
			(fill no)
			(layer "B.Fab")
		)
		(pad "1" smd custom
			(at 0 -0.2794 270)
			(size 0.0762 0.0762)
			(layers "B.Cu" "B.Mask" "B.Paste")
			(net "SAS0_AVDD")
			(options
				(clearance outline)
				(anchor circle)
			)
			(primitives
				(gr_poly
					(pts
						(arc
							(start 0.1524 0.127)
							(mid 0.137521 0.162921)
							(end 0.1016 0.1778)
						)
						(arc
							(start -0.1016 0.1778)
							(mid -0.137521 0.162921)
							(end -0.1524 0.127)
						)
						(arc
							(start -0.1524 -0.127)
							(mid -0.137521 -0.162921)
							(end -0.1016 -0.1778)
						)
						(arc
							(start 0.1016 -0.1778)
							(mid 0.137521 -0.162921)
							(end 0.1524 -0.127)
						)
					)
					(width 0)
					(fill yes)
				)
			)
		)
		(pad "2" smd custom
			(at 0 0.2794 270)
			(size 0.0762 0.0762)
			(layers "B.Cu" "B.Mask" "B.Paste")
			(net "GND")
			(options
				(clearance outline)
				(anchor circle)
			)
			(primitives
				(gr_poly
					(pts
						(arc
							(start 0.1524 0.127)
							(mid 0.137521 0.162921)
							(end 0.1016 0.1778)
						)
						(arc
							(start -0.1016 0.1778)
							(mid -0.137521 0.162921)
							(end -0.1524 0.127)
						)
						(arc
							(start -0.1524 -0.127)
							(mid -0.137521 -0.162921)
							(end -0.1016 -0.1778)
						)
						(arc
							(start 0.1016 -0.1778)
							(mid 0.137521 -0.162921)
							(end 0.1524 -0.127)
						)
					)
					(width 0)
					(fill yes)
				)
			)
		)
	)
	(footprint ""
		(layer "B.Cu")
		(at 38.45941 -120.075452 90)
		(property "Reference" "R339"
			(at 0 0 90)
			(layer "B.SilkS")
			(hide yes)
			(effects
				(font
					(size 1.27 1.27)
				)
				(justify mirror)
			)
		)
		(property "Value" "4K7R2F-GP"
			(at -0.064008 -3.993896 90)
			(unlocked yes)
			(layer "B.Fab")
			(hide yes)
			(effects
				(font
					(size 1.016 1.016)
					(thickness 0.1524)
				)
				(justify mirror)
			)
		)
		(property "Device Type" "R402H16"
			(at -0.064008 -5.517896 90)
			(unlocked yes)
			(layer "B.Fab")
			(hide yes)
			(effects
				(font
					(size 1.016 1.016)
					(thickness 0.1524)
				)
				(justify mirror)
			)
		)
		(duplicate_pad_numbers_are_jumpers no)
		(fp_line
			(start 0.508 -0.9398)
			(end 0.508 0.9398)
			(stroke
				(width 0.1524)
				(type default)
			)
			(layer "B.SilkS")
		)
		(fp_line
			(start -0.508 -0.9398)
			(end 0.508 -0.9398)
			(stroke
				(width 0.1524)
				(type default)
			)
			(layer "B.SilkS")
		)
		(fp_rect
			(start 0.508 0.9398)
			(end -0.508 -0.9398)
			(stroke
				(width 0)
				(type default)
			)
			(fill no)
			(layer "B.CrtYd")
		)
		(fp_rect
			(start 0.508 0.9398)
			(end -0.508 -0.9398)
			(stroke
				(width 0)
				(type default)
			)
			(fill no)
			(layer "B.Fab")
		)
		(pad "1" smd custom
			(at 0 -0.4445 270)
			(size 0.1397 0.1397)
			(layers "B.Cu" "B.Mask" "B.Paste")
			(net "P3V3_STBY")
			(options
				(clearance outline)
				(anchor circle)
			)
			(primitives
				(gr_poly
					(pts
						(arc
							(start -0.1778 0.2794)
							(mid -0.249642 0.249642)
							(end -0.2794 0.1778)
						)
						(arc
							(start -0.2794 -0.1778)
							(mid -0.249642 -0.249642)
							(end -0.1778 -0.2794)
						)
						(arc
							(start 0.1778 -0.2794)
							(mid 0.249642 -0.249642)
							(end 0.2794 -0.1778)
						)
						(arc
							(start 0.2794 0.1778)
							(mid 0.249642 0.249642)
							(end 0.1778 0.2794)
						)
					)
					(width 0)
					(fill yes)
				)
			)
		)
		(pad "2" smd custom
			(at 0 0.4445 270)
			(size 0.1397 0.1397)
			(layers "B.Cu" "B.Mask" "B.Paste")
			(net "TEMP_3_A1")
			(options
				(clearance outline)
				(anchor circle)
			)
			(primitives
				(gr_poly
					(pts
						(arc
							(start -0.1778 0.2794)
							(mid -0.249642 0.249642)
							(end -0.2794 0.1778)
						)
						(arc
							(start -0.2794 -0.1778)
							(mid -0.249642 -0.249642)
							(end -0.1778 -0.2794)
						)
						(arc
							(start 0.1778 -0.2794)
							(mid 0.249642 -0.249642)
							(end 0.2794 -0.1778)
						)
						(arc
							(start 0.2794 0.1778)
							(mid 0.249642 0.249642)
							(end 0.1778 0.2794)
						)
					)
					(width 0)
					(fill yes)
				)
			)
		)
	)
	(footprint ""
		(layer "B.Cu")
		(at 22.011386 -131.007358 180)
		(property "Reference" "R261"
			(at 0 0 0)
			(layer "B.SilkS")
			(hide yes)
			(effects
				(font
					(size 1.27 1.27)
				)
				(justify mirror)
			)
		)
		(property "Value" "120R2F-GP"
			(at -0.064008 -3.993896 180)
			(unlocked yes)
			(layer "B.Fab")
			(hide yes)
			(effects
				(font
					(size 1.016 1.016)
					(thickness 0.1524)
				)
				(justify mirror)
			)
		)
		(property "Device Type" "R402H16"
			(at -0.064008 -5.517896 180)
			(unlocked yes)
			(layer "B.Fab")
			(hide yes)
			(effects
				(font
					(size 1.016 1.016)
					(thickness 0.1524)
				)
				(justify mirror)
			)
		)
		(duplicate_pad_numbers_are_jumpers no)
		(fp_line
			(start 0.508 -0.9398)
			(end 0.508 0.9398)
			(stroke
				(width 0.1524)
				(type default)
			)
			(layer "B.SilkS")
		)
		(fp_line
			(start -0.508 -0.9398)
			(end 0.508 -0.9398)
			(stroke
				(width 0.1524)
				(type default)
			)
			(layer "B.SilkS")
		)
		(fp_rect
			(start 0.508 0.9398)
			(end -0.508 -0.9398)
			(stroke
				(width 0)
				(type default)
			)
			(fill no)
			(layer "B.CrtYd")
		)
		(fp_rect
			(start 0.508 0.9398)
			(end -0.508 -0.9398)
			(stroke
				(width 0)
				(type default)
			)
			(fill no)
			(layer "B.Fab")
		)
		(pad "1" smd custom
			(at 0 -0.4445)
			(size 0.1397 0.1397)
			(layers "B.Cu" "B.Mask" "B.Paste")
			(net "MEMA_13")
			(options
				(clearance outline)
				(anchor circle)
			)
			(primitives
				(gr_poly
					(pts
						(arc
							(start -0.1778 0.2794)
							(mid -0.249642 0.249642)
							(end -0.2794 0.1778)
						)
						(arc
							(start -0.2794 -0.1778)
							(mid -0.249642 -0.249642)
							(end -0.1778 -0.2794)
						)
						(arc
							(start 0.1778 -0.2794)
							(mid 0.249642 -0.249642)
							(end 0.2794 -0.1778)
						)
						(arc
							(start 0.2794 0.1778)
							(mid 0.249642 0.249642)
							(end 0.1778 0.2794)
						)
					)
					(width 0)
					(fill yes)
				)
			)
		)
		(pad "2" smd custom
			(at 0 0.4445)
			(size 0.1397 0.1397)
			(layers "B.Cu" "B.Mask" "B.Paste")
			(net "P1V2_STBY")
			(options
				(clearance outline)
				(anchor circle)
			)
			(primitives
				(gr_poly
					(pts
						(arc
							(start -0.1778 0.2794)
							(mid -0.249642 0.249642)
							(end -0.2794 0.1778)
						)
						(arc
							(start -0.2794 -0.1778)
							(mid -0.249642 -0.249642)
							(end -0.1778 -0.2794)
						)
						(arc
							(start 0.1778 -0.2794)
							(mid 0.249642 -0.249642)
							(end 0.2794 -0.1778)
						)
						(arc
							(start 0.2794 0.1778)
							(mid 0.249642 0.249642)
							(end 0.1778 0.2794)
						)
					)
					(width 0)
					(fill yes)
				)
			)
		)
	)
	(footprint ""
		(layer "B.Cu")
		(at 45.02404 -156.30652 -90)
		(property "Reference" "C102"
			(at 0 0 90)
			(layer "B.SilkS")
			(hide yes)
			(effects
				(font
					(size 1.27 1.27)
				)
				(justify mirror)
			)
		)
		(property "Value" "SC1U16V3KX-5GP"
			(at 0 -2.8194 270)
			(unlocked yes)
			(layer "B.Fab")
			(hide yes)
			(effects
				(font
					(size 1.016 1.016)
					(thickness 0.1524)
				)
				(justify mirror)
			)
		)
		(property "Device Type" "C603H36"
			(at 0 -4.3434 270)
			(unlocked yes)
			(layer "B.Fab")
			(hide yes)
			(effects
				(font
					(size 1.016 1.016)
					(thickness 0.1524)
				)
				(justify mirror)
			)
		)
		(duplicate_pad_numbers_are_jumpers no)
		(fp_line
			(start -0.508 0)
			(end 0.508 0)
			(stroke
				(width 0.2032)
				(type default)
			)
			(layer "B.SilkS")
		)
		(fp_rect
			(start 0.5842 1.3335)
			(end -0.5842 -1.3335)
			(stroke
				(width 0)
				(type default)
			)
			(fill no)
			(layer "B.CrtYd")
		)
		(fp_rect
			(start 0.5842 1.3335)
			(end -0.5842 -1.3335)
			(stroke
				(width 0)
				(type default)
			)
			(fill no)
			(layer "B.Fab")
		)
		(pad "1" smd custom
			(at 0 -0.762 90)
			(size 0.2159 0.2159)
			(layers "B.Cu" "B.Mask" "B.Paste")
			(net "V1PLLAV11")
			(options
				(clearance outline)
				(anchor circle)
			)
			(primitives
				(gr_poly
					(pts
						(arc
							(start -0.3302 0.4318)
							(mid -0.402042 0.402042)
							(end -0.4318 0.3302)
						)
						(arc
							(start -0.4318 -0.3302)
							(mid -0.402042 -0.402042)
							(end -0.3302 -0.4318)
						)
						(arc
							(start 0.3302 -0.4318)
							(mid 0.402042 -0.402042)
							(end 0.4318 -0.3302)
						)
						(arc
							(start 0.4318 0.3302)
							(mid 0.402042 0.402042)
							(end 0.3302 0.4318)
						)
					)
					(width 0)
					(fill yes)
				)
			)
		)
		(pad "2" smd custom
			(at 0 0.762 90)
			(size 0.2159 0.2159)
			(layers "B.Cu" "B.Mask" "B.Paste")
			(net "GND")
			(options
				(clearance outline)
				(anchor circle)
			)
			(primitives
				(gr_poly
					(pts
						(arc
							(start -0.3302 0.4318)
							(mid -0.402042 0.402042)
							(end -0.4318 0.3302)
						)
						(arc
							(start -0.4318 -0.3302)
							(mid -0.402042 -0.402042)
							(end -0.3302 -0.4318)
						)
						(arc
							(start 0.3302 -0.4318)
							(mid 0.402042 -0.402042)
							(end 0.4318 -0.3302)
						)
						(arc
							(start 0.4318 0.3302)
							(mid 0.402042 0.402042)
							(end 0.3302 0.4318)
						)
					)
					(width 0)
					(fill yes)
				)
			)
		)
	)
	(footprint ""
		(layer "B.Cu")
		(at 204.77734 -54.95036)
		(property "Reference" "C446"
			(at 0 0 0)
			(layer "B.SilkS")
			(hide yes)
			(effects
				(font
					(size 1.27 1.27)
				)
				(justify mirror)
			)
		)
		(property "Value" "SCD1U16V2KX-3GP"
			(at -1.1811 -2.7051 0)
			(unlocked yes)
			(layer "B.Fab")
			(hide yes)
			(effects
				(font
					(size 1.016 1.016)
					(thickness 0.1524)
				)
				(justify mirror)
			)
		)
		(property "Device Type" "C402H22"
			(at -1.1811 -4.2291 0)
			(unlocked yes)
			(layer "B.Fab")
			(hide yes)
			(effects
				(font
					(size 1.016 1.016)
					(thickness 0.1524)
				)
				(justify mirror)
			)
		)
		(duplicate_pad_numbers_are_jumpers no)
		(fp_rect
			(start 0.4318 0.9525)
			(end -0.4318 -0.9525)
			(stroke
				(width 0)
				(type default)
			)
			(fill no)
			(layer "B.CrtYd")
		)
		(fp_rect
			(start 0.4318 0.9525)
			(end -0.4318 -0.9525)
			(stroke
				(width 0)
				(type default)
			)
			(fill no)
			(layer "B.Fab")
		)
		(pad "1" smd custom
			(at 0 -0.4445 180)
			(size 0.1524 0.1524)
			(layers "B.Cu" "B.Mask" "B.Paste")
			(net "P1V8")
			(options
				(clearance outline)
				(anchor circle)
			)
			(primitives
				(gr_poly
					(pts
						(arc
							(start 0.3048 0.2032)
							(mid 0.275042 0.275042)
							(end 0.2032 0.3048)
						)
						(arc
							(start -0.2032 0.3048)
							(mid -0.275042 0.275042)
							(end -0.3048 0.2032)
						)
						(arc
							(start -0.3048 -0.2032)
							(mid -0.275042 -0.275042)
							(end -0.2032 -0.3048)
						)
						(arc
							(start 0.2032 -0.3048)
							(mid 0.275042 -0.275042)
							(end 0.3048 -0.2032)
						)
					)
					(width 0)
					(fill yes)
				)
			)
		)
		(pad "2" smd custom
			(at 0 0.4445 180)
			(size 0.1524 0.1524)
			(layers "B.Cu" "B.Mask" "B.Paste")
			(net "GND")
			(options
				(clearance outline)
				(anchor circle)
			)
			(primitives
				(gr_poly
					(pts
						(arc
							(start 0.3048 0.2032)
							(mid 0.275042 0.275042)
							(end 0.2032 0.3048)
						)
						(arc
							(start -0.2032 0.3048)
							(mid -0.275042 0.275042)
							(end -0.3048 0.2032)
						)
						(arc
							(start -0.3048 -0.2032)
							(mid -0.275042 -0.275042)
							(end -0.2032 -0.3048)
						)
						(arc
							(start 0.2032 -0.3048)
							(mid 0.275042 -0.275042)
							(end 0.3048 -0.2032)
						)
					)
					(width 0)
					(fill yes)
				)
			)
		)
	)
	(footprint ""
		(layer "B.Cu")
		(at 192.278 -70.3199)
		(property "Reference" "C371"
			(at 0 0 0)
			(layer "B.SilkS")
			(hide yes)
			(effects
				(font
					(size 1.27 1.27)
				)
				(justify mirror)
			)
		)
		(property "Value" "SCD1U6D3V1KX-GP"
			(at 2.8321 -1.7399 0)
			(unlocked yes)
			(layer "B.Fab")
			(hide yes)
			(effects
				(font
					(size 1.016 1.016)
					(thickness 0.1524)
				)
				(justify mirror)
			)
		)
		(property "Device Type" "C0201H13"
			(at 2.8321 -3.2639 0)
			(unlocked yes)
			(layer "B.Fab")
			(hide yes)
			(effects
				(font
					(size 1.016 1.016)
					(thickness 0.1524)
				)
				(justify mirror)
			)
		)
		(duplicate_pad_numbers_are_jumpers no)
		(fp_rect
			(start 0.2794 0.6477)
			(end -0.2794 -0.6477)
			(stroke
				(width 0)
				(type default)
			)
			(fill no)
			(layer "B.CrtYd")
		)
		(fp_rect
			(start 0.2794 0.6477)
			(end -0.2794 -0.6477)
			(stroke
				(width 0)
				(type default)
			)
			(fill no)
			(layer "B.Fab")
		)
		(pad "1" smd custom
			(at 0 -0.2794 180)
			(size 0.0762 0.0762)
			(layers "B.Cu" "B.Mask" "B.Paste")
			(net "PCE_AVDD")
			(options
				(clearance outline)
				(anchor circle)
			)
			(primitives
				(gr_poly
					(pts
						(arc
							(start 0.1524 0.127)
							(mid 0.137521 0.162921)
							(end 0.1016 0.1778)
						)
						(arc
							(start -0.1016 0.1778)
							(mid -0.137521 0.162921)
							(end -0.1524 0.127)
						)
						(arc
							(start -0.1524 -0.127)
							(mid -0.137521 -0.162921)
							(end -0.1016 -0.1778)
						)
						(arc
							(start 0.1016 -0.1778)
							(mid 0.137521 -0.162921)
							(end 0.1524 -0.127)
						)
					)
					(width 0)
					(fill yes)
				)
			)
		)
		(pad "2" smd custom
			(at 0 0.2794 180)
			(size 0.0762 0.0762)
			(layers "B.Cu" "B.Mask" "B.Paste")
			(net "GND")
			(options
				(clearance outline)
				(anchor circle)
			)
			(primitives
				(gr_poly
					(pts
						(arc
							(start 0.1524 0.127)
							(mid 0.137521 0.162921)
							(end 0.1016 0.1778)
						)
						(arc
							(start -0.1016 0.1778)
							(mid -0.137521 0.162921)
							(end -0.1524 0.127)
						)
						(arc
							(start -0.1524 -0.127)
							(mid -0.137521 -0.162921)
							(end -0.1016 -0.1778)
						)
						(arc
							(start 0.1016 -0.1778)
							(mid 0.137521 -0.162921)
							(end 0.1524 -0.127)
						)
					)
					(width 0)
					(fill yes)
				)
			)
		)
	)
	(footprint ""
		(layer "B.Cu")
		(at 210.510374 -58.689494 -90)
		(property "Reference" "TP142"
			(at 0 0 90)
			(layer "B.SilkS")
			(hide yes)
			(effects
				(font
					(size 1.27 1.27)
				)
				(justify mirror)
			)
		)
		(property "Value" "TPAD28-2-GP"
			(at 0.0127 -1.6637 270)
			(unlocked yes)
			(layer "B.Fab")
			(hide yes)
			(effects
				(font
					(size 1.016 1.016)
					(thickness 0.1524)
				)
				(justify mirror)
			)
		)
		(property "Device Type" "TPAD28"
			(at 0.0127 -3.1877 270)
			(unlocked yes)
			(layer "B.Fab")
			(hide yes)
			(effects
				(font
					(size 1.016 1.016)
					(thickness 0.1524)
				)
				(justify mirror)
			)
		)
		(duplicate_pad_numbers_are_jumpers no)
		(fp_poly
			(pts
				(arc
					(start 0 -0.3556)
					(mid 0 0.3556)
					(end 0 -0.3556)
				)
			)
			(stroke
				(width 0)
				(type default)
			)
			(fill no)
			(layer "B.CrtYd")
		)
		(fp_poly
			(pts
				(arc
					(start 0 -0.6096)
					(mid 0 0.6096)
					(end 0 -0.6096)
				)
			)
			(stroke
				(width 0)
				(type default)
			)
			(fill no)
			(layer "B.Fab")
		)
		(pad "1" smd circle
			(at 0 0 90)
			(size 0.7112 0.7112)
			(layers "B.Cu" "B.Mask" "B.Paste")
			(net "ICE1_TDI")
		)
	)
	(footprint ""
		(layer "B.Cu")
		(at 178.4096 -72.8218)
		(property "Reference" "TP102"
			(at 0 0 0)
			(layer "B.SilkS")
			(hide yes)
			(effects
				(font
					(size 1.27 1.27)
				)
				(justify mirror)
			)
		)
		(property "Value" "TPAD28-2-GP"
			(at 0.0127 -1.6637 0)
			(unlocked yes)
			(layer "B.Fab")
			(hide yes)
			(effects
				(font
					(size 1.016 1.016)
					(thickness 0.1524)
				)
				(justify mirror)
			)
		)
		(property "Device Type" "TPAD28"
			(at 0.0127 -3.1877 0)
			(unlocked yes)
			(layer "B.Fab")
			(hide yes)
			(effects
				(font
					(size 1.016 1.016)
					(thickness 0.1524)
				)
				(justify mirror)
			)
		)
		(duplicate_pad_numbers_are_jumpers no)
		(fp_poly
			(pts
				(arc
					(start 0.3556 0)
					(mid -0.3556 0)
					(end 0.3556 0)
				)
			)
			(stroke
				(width 0)
				(type default)
			)
			(fill no)
			(layer "B.CrtYd")
		)
		(fp_poly
			(pts
				(arc
					(start 0.6096 0)
					(mid -0.6096 0)
					(end 0.6096 0)
				)
			)
			(stroke
				(width 0)
				(type default)
			)
			(fill no)
			(layer "B.Fab")
		)
		(pad "1" smd circle
			(at 0 0 180)
			(size 0.7112 0.7112)
			(layers "B.Cu" "B.Mask" "B.Paste")
			(net "IOC_GPIO_17")
		)
	)
	(footprint ""
		(layer "B.Cu")
		(at 183.632094 -76.449428)
		(property "Reference" "TP156"
			(at 0 0 0)
			(layer "B.SilkS")
			(hide yes)
			(effects
				(font
					(size 1.27 1.27)
				)
				(justify mirror)
			)
		)
		(property "Value" "TPAD28-2-GP"
			(at 0.0127 -1.6637 0)
			(unlocked yes)
			(layer "B.Fab")
			(hide yes)
			(effects
				(font
					(size 1.016 1.016)
					(thickness 0.1524)
				)
				(justify mirror)
			)
		)
		(property "Device Type" "TPAD28"
			(at 0.0127 -3.1877 0)
			(unlocked yes)
			(layer "B.Fab")
			(hide yes)
			(effects
				(font
					(size 1.016 1.016)
					(thickness 0.1524)
				)
				(justify mirror)
			)
		)
		(duplicate_pad_numbers_are_jumpers no)
		(fp_poly
			(pts
				(arc
					(start 0.3556 0)
					(mid -0.3556 0)
					(end 0.3556 0)
				)
			)
			(stroke
				(width 0)
				(type default)
			)
			(fill no)
			(layer "B.CrtYd")
		)
		(fp_poly
			(pts
				(arc
					(start 0.6096 0)
					(mid -0.6096 0)
					(end 0.6096 0)
				)
			)
			(stroke
				(width 0)
				(type default)
			)
			(fill no)
			(layer "B.Fab")
		)
		(pad "1" smd circle
			(at 0 0 180)
			(size 0.7112 0.7112)
			(layers "B.Cu" "B.Mask" "B.Paste")
			(net "SPARE0")
		)
	)
)
